#ISCELL
  pure_quanta quanta_title_block_c *
  *
#ISCELL
  pure_quanta_power cad_note *
  *
#CELL
  pure_quanta genoa_sp5 *
  page19_i159
#ISCELL
  mstr_standard offpage *
  page19_i160
#ISCELL
  mstr_standard offpage *
  page19_i161
#ISCELL
  mstr_standard tap *
  page19_i162
#ISCELL
  mstr_standard tap *
  page19_i163
#ISCELL
  mstr_standard tap *
  page19_i164
#ISCELL
  mstr_standard tap *
  page19_i165
#ISCELL
  mstr_standard tap *
  page19_i166
#ISCELL
  mstr_standard tap *
  page19_i167
#ISCELL
  mstr_standard tap *
  page19_i168
#ISCELL
  mstr_standard tap *
  page19_i169
#ISCELL
  mstr_standard tap *
  page19_i170
#ISCELL
  mstr_standard tap *
  page19_i171
#ISCELL
  mstr_standard tap *
  page19_i172
#ISCELL
  mstr_standard tap *
  page19_i173
#ISCELL
  mstr_standard tap *
  page19_i174
#ISCELL
  mstr_standard tap *
  page19_i175
#ISCELL
  mstr_standard tap *
  page19_i176
#ISCELL
  mstr_standard tap *
  page19_i177
#ISCELL
  mstr_standard tap *
  page19_i178
#ISCELL
  mstr_standard tap *
  page19_i179
#ISCELL
  mstr_standard tap *
  page19_i180
#ISCELL
  mstr_standard tap *
  page19_i181
#ISCELL
  mstr_standard tap *
  page19_i182
#ISCELL
  mstr_standard tap *
  page19_i183
#ISCELL
  mstr_standard tap *
  page19_i184
#ISCELL
  mstr_standard tap *
  page19_i185
#ISCELL
  mstr_standard tap *
  page19_i186
#ISCELL
  mstr_standard tap *
  page19_i187
#ISCELL
  mstr_standard tap *
  page19_i188
#ISCELL
  mstr_standard tap *
  page19_i189
#ISCELL
  mstr_standard tap *
  page19_i190
#ISCELL
  mstr_standard tap *
  page19_i191
#ISCELL
  mstr_standard tap *
  page19_i192
#ISCELL
  mstr_standard tap *
  page19_i193
#ISCELL
  mstr_standard tap *
  page19_i194
#ISCELL
  mstr_standard tap *
  page19_i195
#ISCELL
  mstr_standard tap *
  page19_i196
#ISCELL
  mstr_standard offpage *
  page19_i197
#ISCELL
  mstr_standard tap *
  page19_i198
#ISCELL
  mstr_standard tap *
  page19_i199
#ISCELL
  mstr_standard tap *
  page19_i200
#ISCELL
  mstr_standard tap *
  page19_i201
#ISCELL
  mstr_standard tap *
  page19_i202
#ISCELL
  mstr_standard tap *
  page19_i203
#ISCELL
  mstr_standard tap *
  page19_i204
#ISCELL
  mstr_standard tap *
  page19_i205
#ISCELL
  mstr_standard tap *
  page19_i206
#ISCELL
  mstr_standard tap *
  page19_i207
#ISCELL
  mstr_standard tap *
  page19_i208
#ISCELL
  mstr_standard tap *
  page19_i209
#ISCELL
  mstr_standard tap *
  page19_i210
#ISCELL
  mstr_standard tap *
  page19_i211
#ISCELL
  mstr_standard tap *
  page19_i212
#ISCELL
  mstr_standard tap *
  page19_i213
#ISCELL
  mstr_standard tap *
  page19_i214
#ISCELL
  mstr_standard tap *
  page19_i215
#ISCELL
  mstr_standard tap *
  page19_i216
#ISCELL
  mstr_standard tap *
  page19_i217
#ISCELL
  mstr_standard tap *
  page19_i218
#ISCELL
  mstr_standard tap *
  page19_i219
#ISCELL
  mstr_standard tap *
  page19_i220
#ISCELL
  mstr_standard tap *
  page19_i221
#ISCELL
  mstr_standard tap *
  page19_i222
#ISCELL
  mstr_standard tap *
  page19_i223
#ISCELL
  mstr_standard tap *
  page19_i224
#ISCELL
  mstr_standard tap *
  page19_i225
#ISCELL
  mstr_standard tap *
  page19_i226
#ISCELL
  mstr_standard tap *
  page19_i227
#ISCELL
  mstr_standard tap *
  page19_i228
#ISCELL
  mstr_standard tap *
  page19_i229
#ISCELL
  mstr_standard tap *
  page19_i230
#ISCELL
  mstr_standard tap *
  page19_i231
#ISCELL
  mstr_standard tap *
  page19_i232
#ISCELL
  mstr_standard tap *
  page19_i233
#ISCELL
  mstr_standard tap *
  page19_i234
#ISCELL
  mstr_standard offpage *
  page19_i235
#ISCELL
  mstr_standard tap *
  page19_i236
#ISCELL
  mstr_standard tap *
  page19_i237
#ISCELL
  mstr_standard tap *
  page19_i238
#ISCELL
  mstr_standard tap *
  page19_i239
#ISCELL
  mstr_standard tap *
  page19_i240
#ISCELL
  mstr_standard tap *
  page19_i241
#ISCELL
  mstr_standard tap *
  page19_i242
#ISCELL
  mstr_standard tap *
  page19_i243
#ISCELL
  mstr_standard tap *
  page19_i244
#ISCELL
  mstr_standard tap *
  page19_i245
#ISCELL
  mstr_standard tap *
  page19_i246
#ISCELL
  mstr_standard tap *
  page19_i247
#ISCELL
  mstr_standard tap *
  page19_i248
#ISCELL
  mstr_standard tap *
  page19_i249
#ISCELL
  mstr_standard tap *
  page19_i250
#ISCELL
  mstr_standard tap *
  page19_i251
#ISCELL
  mstr_standard tap *
  page19_i252
#ISCELL
  mstr_standard tap *
  page19_i253
#ISCELL
  mstr_standard tap *
  page19_i254
#ISCELL
  mstr_standard tap *
  page19_i255
#ISCELL
  mstr_standard tap *
  page19_i256
#ISCELL
  mstr_standard tap *
  page19_i257
#ISCELL
  mstr_standard tap *
  page19_i258
#ISCELL
  mstr_standard tap *
  page19_i259
#ISCELL
  mstr_standard tap *
  page19_i260
#ISCELL
  mstr_standard tap *
  page19_i261
#ISCELL
  mstr_standard tap *
  page19_i262
#ISCELL
  mstr_standard tap *
  page19_i263
#ISCELL
  mstr_standard tap *
  page19_i264
#ISCELL
  mstr_standard tap *
  page19_i265
#ISCELL
  mstr_standard tap *
  page19_i266
#ISCELL
  mstr_standard tap *
  page19_i267
#ISCELL
  mstr_standard tap *
  page19_i268
#ISCELL
  mstr_standard tap *
  page19_i269
#ISCELL
  mstr_standard tap *
  page19_i270
#ISCELL
  mstr_standard tap *
  page19_i271
#ISCELL
  mstr_standard tap *
  page19_i272
#ISCELL
  mstr_standard tap *
  page19_i273
#ISCELL
  mstr_standard tap *
  page19_i274
#ISCELL
  mstr_standard tap *
  page19_i275
#ISCELL
  mstr_standard tap *
  page19_i276
#ISCELL
  mstr_standard tap *
  page19_i277
#ISCELL
  mstr_standard tap *
  page19_i278
#ISCELL
  mstr_standard tap *
  page19_i279
#ISCELL
  mstr_standard tap *
  page19_i280
#ISCELL
  mstr_standard tap *
  page19_i281
#ISCELL
  standard offpage *
  page19_i282
#ISCELL
  standard offpage *
  page19_i283
#ISCELL
  standard offpage *
  page19_i284
#ISCELL
  standard offpage *
  page19_i285
#ISCELL
  mstr_standard tap *
  page19_i286
#ISCELL
  mstr_standard tap *
  page19_i287
#ISCELL
  mstr_standard tap *
  page19_i288
#ISCELL
  mstr_standard tap *
  page19_i289
#ISCELL
  mstr_standard tap *
  page19_i290
#ISCELL
  mstr_standard tap *
  page19_i291
#ISCELL
  mstr_standard tap *
  page19_i292
#ISCELL
  mstr_standard tap *
  page19_i293
#ISCELL
  mstr_standard tap *
  page19_i294
#ISCELL
  mstr_standard tap *
  page19_i295
#ISCELL
  mstr_standard tap *
  page19_i296
#ISCELL
  mstr_standard tap *
  page19_i297
#ISCELL
  mstr_standard tap *
  page19_i298
#ISCELL
  mstr_standard tap *
  page19_i299
#ISCELL
  mstr_standard tap *
  page19_i300
#ISCELL
  mstr_standard tap *
  page19_i301
#ISCELL
  standard offpage *
  page19_i302
#ISCELL
  standard offpage *
  page19_i303
#ISCELL
  standard offpage *
  page19_i304
#ISCELL
  standard offpage *
  page19_i305
#ISCELL
  standard offpage *
  page19_i306
#ISCELL
  mstr_standard offpage *
  page19_i307
#ISCELL
  standard offpage *
  page19_i308
#ISCELL
  standard offpage *
  page19_i309
#ISCELL
  standard offpage *
  page19_i310
#ISCELL
  standard offpage *
  page19_i311
#ISCELL
  standard offpage *
  page19_i312
#ISCELL
  standard offpage *
  page19_i313
#CELL
  pure_quanta q_res *
  page19_i314
#ISCELL
  mstr_standard offpage *
  page19_i315
#ISCELL
  standard offpage *
  page19_i316
